# S9S_MB_2U (Grand Teton) — schematic netlist excerpt (pin names and nets, part order shuffled) for the footprints in the layout excerpt that follows; sources: Cadence DE-HDL packaged netlist, KiCad conversion of 03242023_DA0F0TMBIJ0_F0T_Motherboard_J_brd_V01_OCP.brd

R1710  Q_RES  49.9 1% CHIP  pkg 0402LF  page 215 : A = FM_PLD_REV_N ; B = FM_PLD_REV_R_N
PC1358  Q_CAP  0.1UF 25V 10% X7R  pkg 0402  page 286 : A = GND ; B = PVCCIN_CPU1_VREF

(kicad_pcb
	(version 20260206)
	(generator "pcbnew")
	(generator_version "10.0")
	(general
		(thickness 1.6)
		(legacy_teardrops no)
	)
	(paper "A4")
	(title_block
		(title "03242023_DA0F0TMBIJ0_F0T_Motherboard_J_brd_V01_OCP.brd")
		(comment 1 "Grand Teton / footprints 251-252 of 6105")
	)
	(layers
		(0 "F.Cu" signal "TOP")
		(4 "In1.Cu" signal "GND")
		(6 "In2.Cu" signal "IN1")
		(8 "In3.Cu" signal "GND1")
		(10 "In4.Cu" signal "IN2")
		(12 "In5.Cu" signal "GND2")
		(14 "In6.Cu" signal "IN3")
		(16 "In7.Cu" signal "GND3")
		(18 "In8.Cu" signal "VCC")
		(20 "In9.Cu" signal "VCC1")
		(22 "In10.Cu" signal "GND4")
		(24 "In11.Cu" signal "IN4")
		(26 "In12.Cu" signal "GND5")
		(28 "In13.Cu" signal "IN5")
		(30 "In14.Cu" signal "GND6")
		(32 "In15.Cu" signal "IN6")
		(34 "In16.Cu" signal "GND7")
		(2 "B.Cu" signal "BOTTOM")
		(9 "F.Adhes" user "F.Adhesive")
		(11 "B.Adhes" user "B.Adhesive")
		(13 "F.Paste" user "Package Geometry/Pastemask Top")
		(15 "B.Paste" user "Package Geometry/Pastemask Bottom")
		(5 "F.SilkS" user "Ref Des/Silkscreen Top")
		(7 "B.SilkS" user "Ref Des/Silkscreen Bottom")
		(1 "F.Mask" user "Board Geometry/Soldermask Top")
		(3 "B.Mask" user "Board Geometry/Soldermask Bottom")
		(17 "Dwgs.User" user "User.Drawings")
		(19 "Cmts.User" user "User.Comments")
		(21 "Eco1.User" user "User.Eco1")
		(23 "Eco2.User" user "User.Eco2")
		(25 "Edge.Cuts" user "Board Geometry/Outline")
		(27 "Margin" user)
		(31 "F.CrtYd" user "Package Geometry/Place Bound Top")
		(29 "B.CrtYd" user "Package Geometry/Place Bound Bottom")
		(35 "F.Fab" user "Ref Des/Assembly Top")
		(33 "B.Fab" user "Ref Des/Assembly Bottom")
	)
	(footprint ""
		(layer "F.Cu")
		(at 118.781576 -338.3026 -90)
		(property "Reference" "PC1358"
			(at 0 0 270)
			(layer "F.SilkS")
			(hide yes)
			(effects
				(font
					(size 1.27 1.27)
				)
			)
		)
		(property "Value" ""
			(at 0 0 270)
			(layer "F.Fab")
			(effects
				(font
					(size 1.27 1.27)
				)
			)
		)
		(duplicate_pad_numbers_are_jumpers no)
		(fp_line
			(start -0.7874 0.4064)
			(end -0.7874 -0.4064)
			(stroke
				(width 0.1524)
				(type default)
			)
			(layer "F.SilkS")
		)
		(fp_line
			(start 0.7874 0.4064)
			(end -0.7874 0.4064)
			(stroke
				(width 0.1524)
				(type default)
			)
			(layer "F.SilkS")
		)
		(fp_line
			(start -0.7874 -0.4064)
			(end 0.7874 -0.4064)
			(stroke
				(width 0.1524)
				(type default)
			)
			(layer "F.SilkS")
		)
		(fp_line
			(start 0.7874 -0.4064)
			(end 0.7874 0.4064)
			(stroke
				(width 0.1524)
				(type default)
			)
			(layer "F.SilkS")
		)
		(fp_line
			(start -0.67945 0.3048)
			(end -0.67945 -0.305054)
			(stroke
				(width 0.1)
				(type default)
			)
			(layer "F.Fab")
		)
		(fp_line
			(start -0.12065 0.3048)
			(end -0.67945 0.3048)
			(stroke
				(width 0.1)
				(type default)
			)
			(layer "F.Fab")
		)
		(fp_line
			(start 0.120396 0.3048)
			(end 0.120396 0.2794)
			(stroke
				(width 0.1)
				(type default)
			)
			(layer "F.Fab")
		)
		(fp_line
			(start 0.67945 0.3048)
			(end 0.120396 0.3048)
			(stroke
				(width 0.1)
				(type default)
			)
			(layer "F.Fab")
		)
		(fp_line
			(start -0.12065 0.2794)
			(end -0.12065 0.3048)
			(stroke
				(width 0.1)
				(type default)
			)
			(layer "F.Fab")
		)
		(fp_line
			(start 0.120396 0.2794)
			(end -0.12065 0.2794)
			(stroke
				(width 0.1)
				(type default)
			)
			(layer "F.Fab")
		)
		(fp_line
			(start -0.12065 -0.2794)
			(end 0.12065 -0.2794)
			(stroke
				(width 0.1)
				(type default)
			)
			(layer "F.Fab")
		)
		(fp_line
			(start 0.12065 -0.2794)
			(end 0.12065 -0.3048)
			(stroke
				(width 0.1)
				(type default)
			)
			(layer "F.Fab")
		)
		(fp_line
			(start 0.12065 -0.3048)
			(end 0.67945 -0.3048)
			(stroke
				(width 0.1)
				(type default)
			)
			(layer "F.Fab")
		)
		(fp_line
			(start 0.67945 -0.3048)
			(end 0.67945 0.3048)
			(stroke
				(width 0.1)
				(type default)
			)
			(layer "F.Fab")
		)
		(fp_line
			(start -0.67945 -0.305054)
			(end -0.12065 -0.305054)
			(stroke
				(width 0.1)
				(type default)
			)
			(layer "F.Fab")
		)
		(fp_line
			(start -0.12065 -0.305054)
			(end -0.12065 -0.2794)
			(stroke
				(width 0.1)
				(type default)
			)
			(layer "F.Fab")
		)
		(pad "1" smd circle
			(at -0.40005 0 270)
			(size 0 0)
			(layers "F.Cu" "F.Mask" "F.Paste")
			(net "GND")
		)
		(pad "2" smd circle
			(at 0.40005 0 270)
			(size 0 0)
			(layers "F.Cu" "F.Mask" "F.Paste")
			(net "PVCCIN_CPU1_VREF")
		)
	)
	(footprint ""
		(layer "F.Cu")
		(at 197.19036 -124.170948)
		(property "Reference" "R1710"
			(at 0 0 0)
			(layer "F.SilkS")
			(hide yes)
			(effects
				(font
					(size 1.27 1.27)
				)
			)
		)
		(property "Value" ""
			(at 0 0 0)
			(layer "F.Fab")
			(effects
				(font
					(size 1.27 1.27)
				)
			)
		)
		(duplicate_pad_numbers_are_jumpers no)
		(fp_line
			(start -0.7874 -0.4064)
			(end 0.7874 -0.4064)
			(stroke
				(width 0.1524)
				(type default)
			)
			(layer "F.SilkS")
		)
		(fp_line
			(start -0.7874 0.4064)
			(end -0.7874 -0.4064)
			(stroke
				(width 0.1524)
				(type default)
			)
			(layer "F.SilkS")
		)
		(fp_line
			(start 0.7874 -0.4064)
			(end 0.7874 0.4064)
			(stroke
				(width 0.1524)
				(type default)
			)
			(layer "F.SilkS")
		)
		(fp_line
			(start 0.7874 0.4064)
			(end -0.7874 0.4064)
			(stroke
				(width 0.1524)
				(type default)
			)
			(layer "F.SilkS")
		)
		(fp_line
			(start -0.67945 -0.305054)
			(end -0.12065 -0.305054)
			(stroke
				(width 0.1)
				(type default)
			)
			(layer "F.Fab")
		)
		(fp_line
			(start -0.67945 0.3048)
			(end -0.67945 -0.305054)
			(stroke
				(width 0.1)
				(type default)
			)
			(layer "F.Fab")
		)
		(fp_line
			(start -0.12065 -0.305054)
			(end -0.12065 -0.2794)
			(stroke
				(width 0.1)
				(type default)
			)
			(layer "F.Fab")
		)
		(fp_line
			(start -0.12065 -0.2794)
			(end 0.12065 -0.2794)
			(stroke
				(width 0.1)
				(type default)
			)
			(layer "F.Fab")
		)
		(fp_line
			(start -0.12065 0.2794)
			(end -0.12065 0.3048)
			(stroke
				(width 0.1)
				(type default)
			)
			(layer "F.Fab")
		)
		(fp_line
			(start -0.12065 0.3048)
			(end -0.67945 0.3048)
			(stroke
				(width 0.1)
				(type default)
			)
			(layer "F.Fab")
		)
		(fp_line
			(start 0.120396 0.2794)
			(end -0.12065 0.2794)
			(stroke
				(width 0.1)
				(type default)
			)
			(layer "F.Fab")
		)
		(fp_line
			(start 0.120396 0.3048)
			(end 0.120396 0.2794)
			(stroke
				(width 0.1)
				(type default)
			)
			(layer "F.Fab")
		)
		(fp_line
			(start 0.12065 -0.3048)
			(end 0.67945 -0.3048)
			(stroke
				(width 0.1)
				(type default)
			)
			(layer "F.Fab")
		)
		(fp_line
			(start 0.12065 -0.2794)
			(end 0.12065 -0.3048)
			(stroke
				(width 0.1)
				(type default)
			)
			(layer "F.Fab")
		)
		(fp_line
			(start 0.67945 -0.3048)
			(end 0.67945 0.3048)
			(stroke
				(width 0.1)
				(type default)
			)
			(layer "F.Fab")
		)
		(fp_line
			(start 0.67945 0.3048)
			(end 0.120396 0.3048)
			(stroke
				(width 0.1)
				(type default)
			)
			(layer "F.Fab")
		)
		(pad "1" smd circle
			(at -0.40005 0)
			(size 0 0)
			(layers "F.Cu" "F.Mask" "F.Paste")
			(net "FM_PLD_REV_N")
		)
		(pad "2" smd circle
			(at 0.40005 0)
			(size 0 0)
			(layers "F.Cu" "F.Mask" "F.Paste")
			(net "FM_PLD_REV_R_N")
		)
	)
)
